(kicad_pcb
	(version 20241229)
	(generator "pcbnew")
	(generator_version "9.0")
	(general
		(thickness 1.62)
		(legacy_teardrops no)
	)
	(paper "A4")
	(title_block
		(title "OCuLink to 10GbE adapter")
		(date "2026-02-23")
		(rev "1.1.0")
		(company "Antmicro Ltd")
		(comment 1 "www.antmicro.com")
		(comment 9 "footprints 10-12 of 510")
	)
	(layers
		(0 "F.Cu" signal)
		(4 "In1.Cu" signal)
		(6 "In2.Cu" signal)
		(8 "In3.Cu" signal)
		(10 "In4.Cu" signal)
		(12 "In5.Cu" signal)
		(14 "In6.Cu" signal)
		(2 "B.Cu" signal)
		(9 "F.Adhes" user "F.Adhesive")
		(11 "B.Adhes" user "B.Adhesive")
		(13 "F.Paste" user)
		(15 "B.Paste" user)
		(5 "F.SilkS" user "F.Silkscreen")
		(7 "B.SilkS" user "B.Silkscreen")
		(1 "F.Mask" user)
		(3 "B.Mask" user)
		(17 "Dwgs.User" user "User.Drawings")
		(19 "Cmts.User" user "User.Comments")
		(21 "Eco1.User" user "User.Eco1")
		(23 "Eco2.User" user "User.Eco2")
		(25 "Edge.Cuts" user)
		(27 "Margin" user)
		(31 "F.CrtYd" user "F.Courtyard")
		(29 "B.CrtYd" user "B.Courtyard")
		(35 "F.Fab" user)
		(33 "B.Fab" user)
	)
	(footprint "antmicro-footprints:Amphenol_G14A421211112HR"
		(layer "F.Cu")
		(at 100 53.385001 180)
		(property "Reference" "J9"
			(at 7.95 -6.2 0)
			(unlocked yes)
			(layer "F.SilkS")
			(effects
				(font
					(size 0.7 0.7)
					(thickness 0.15)
				)
				(justify left bottom)
			)
		)
		(property "Value" "OCuLink_x4_Amphenol_G14A421211112HR_CUSTOM_device_side"
			(at 0 6.385 180)
			(unlocked yes)
			(layer "F.Fab")
			(hide yes)
			(effects
				(font
					(size 0.7 0.7)
					(thickness 0.15)
				)
				(justify left bottom)
			)
		)
		(property "Datasheet" "https://cdn.amphenol-cs.com/media/wysiwyg/files/drawing/g14a421x1bxxxhr.pdf"
			(at 0 0 0)
			(layer "F.Fab")
			(hide yes)
			(effects
				(font
					(size 1.27 1.27)
					(thickness 0.15)
				)
			)
		)
		(property "Description" "I/O Connectors OCulink, Receptacle, 0.5mm pitch, 4X, R/A SMT with shell leg SMT type, 30U\" gold plating, LCP, black, T&R packing"
			(at 0 0 0)
			(layer "F.Fab")
			(hide yes)
			(effects
				(font
					(size 1.27 1.27)
					(thickness 0.15)
				)
			)
		)
		(property "Manufacturer" "Amphenol"
			(at 0 0 180)
			(unlocked yes)
			(layer "F.Fab")
			(hide yes)
			(effects
				(font
					(size 1 1)
					(thickness 0.15)
				)
			)
		)
		(property "MPN" "G14A421211112HR"
			(at 0 0 180)
			(unlocked yes)
			(layer "F.Fab")
			(hide yes)
			(effects
				(font
					(size 1 1)
					(thickness 0.15)
				)
			)
		)
		(property "Author" "Antmicro"
			(at 0 0 180)
			(unlocked yes)
			(layer "F.Fab")
			(hide yes)
			(effects
				(font
					(size 1 1)
					(thickness 0.15)
				)
			)
		)
		(property "License" "Apache-2.0"
			(at 0 0 180)
			(unlocked yes)
			(layer "F.Fab")
			(hide yes)
			(effects
				(font
					(size 1 1)
					(thickness 0.15)
				)
			)
		)
		(sheetname "/OCuLink/")
		(sheetfile "oculink.kicad_sch")
		(solder_paste_margin -0.06)
		(attr smd)
		(fp_line
			(start 6.8 -3)
			(end 6.8 -0.4)
			(stroke
				(width 0.1)
				(type default)
			)
			(layer "F.SilkS")
		)
		(fp_line
			(start -6.8 -0.4)
			(end -6.8 -3)
			(stroke
				(width 0.1)
				(type default)
			)
			(layer "F.SilkS")
		)
		(fp_circle
			(center -5.3 -5.52)
			(end -5.25 -5.52)
			(stroke
				(width 0.15)
				(type solid)
			)
			(fill yes)
			(layer "F.SilkS")
		)
		(fp_rect
			(start -8.22 -5.22)
			(end 8.22 4.94)
			(stroke
				(width 0.05)
				(type solid)
			)
			(fill no)
			(layer "F.CrtYd")
		)
		(fp_line
			(start 7 3.065)
			(end -7 3.065)
			(stroke
				(width 0.1)
				(type default)
			)
			(layer "F.Fab")
		)
		(fp_text user "${REFERENCE}"
			(at -8.22 9.885 180)
			(unlocked yes)
			(layer "F.Fab")
			(effects
				(font
					(size 0.7 0.7)
					(thickness 0.15)
				)
				(justify left bottom)
			)
		)
		(fp_text user "Author: Antmicro"
			(at -8.22 11.085 180)
			(layer "F.Fab")
			(effects
				(font
					(size 0.7 0.7)
					(thickness 0.15)
				)
				(justify left bottom)
			)
		)
		(fp_text user "License: Apache-2.0"
			(at -8.22 12.285 180)
			(layer "F.Fab")
			(effects
				(font
					(size 0.7 0.7)
					(thickness 0.15)
				)
				(justify left bottom)
			)
		)
		(fp_text user "PCB EDGE"
			(at 2.8 2.95 180)
			(unlocked yes)
			(layer "F.Fab")
			(effects
				(font
					(size 0.5 0.5)
					(thickness 0.125)
				)
				(justify left bottom)
			)
		)
		(pad "" np_thru_hole circle
			(at -5.42 -1.395 270)
			(size 1 1)
			(drill 1)
			(layers "*.Cu" "*.Mask")
		)
		(pad "" np_thru_hole circle
			(at 5.95 -1.395 270)
			(size 1 1)
			(drill 1)
			(layers "*.Cu" "*.Mask")
		)
		(pad "A1" smd roundrect
			(at -4.75 -2.115 270)
			(size 0.91 0.31)
			(layers "F.Cu" "F.Mask" "F.Paste")
			(roundrect_rratio 0.5)
			(net 90 "+3V3_AUX")
			(pinfunction "V_{ACT}_RX_3V3")
			(pintype "power_in")
		)
		(pad "A2" smd roundrect
			(at -4.25 -2.115 270)
			(size 0.91 0.31)
			(layers "F.Cu" "F.Mask" "F.Paste")
			(roundrect_rratio 0.5)
			(net 28 "GND")
			(pinfunction "GND")
			(pintype "passive")
		)
		(pad "A3" smd roundrect
			(at -3.75 -2.115 270)
			(size 0.91 0.31)
			(layers "F.Cu" "F.Mask" "F.Paste")
			(roundrect_rratio 0.5)
			(net 39 "/OCuLink/PCIe_{x4}.RX0+")
			(pinfunction "PER0+")
			(pintype "output")
		)
		(pad "A4" smd roundrect
			(at -3.25 -2.115 270)
			(size 0.91 0.31)
			(layers "F.Cu" "F.Mask" "F.Paste")
			(roundrect_rratio 0.5)
			(net 36 "/OCuLink/PCIe_{x4}.RX0-")
			(pinfunction "PER0-")
			(pintype "output")
		)
		(pad "A5" smd roundrect
			(at -2.75 -2.115 270)
			(size 0.91 0.31)
			(layers "F.Cu" "F.Mask" "F.Paste")
			(roundrect_rratio 0.5)
			(net 28 "GND")
			(pinfunction "GND")
			(pintype "passive")
		)
		(pad "A6" smd roundrect
			(at -2.25 -2.115 270)
			(size 0.91 0.31)
			(layers "F.Cu" "F.Mask" "F.Paste")
			(roundrect_rratio 0.5)
			(net 37 "/OCuLink/PCIe_{x4}.RX1+")
			(pinfunction "PER1+")
			(pintype "output")
		)
		(pad "A7" smd roundrect
			(at -1.75 -2.115 270)
			(size 0.91 0.31)
			(layers "F.Cu" "F.Mask" "F.Paste")
			(roundrect_rratio 0.5)
			(net 34 "/OCuLink/PCIe_{x4}.RX1-")
			(pinfunction "PER1-")
			(pintype "output")
		)
		(pad "A8" smd roundrect
			(at -1.25 -2.115 270)
			(size 0.91 0.31)
			(layers "F.Cu" "F.Mask" "F.Paste")
			(roundrect_rratio 0.5)
			(net 28 "GND")
			(pinfunction "GND")
			(pintype "passive")
		)
		(pad "A9" smd roundrect
			(at -0.75 -2.115 270)
			(size 0.91 0.31)
			(layers "F.Cu" "F.Mask" "F.Paste")
			(roundrect_rratio 0.5)
			(net 304 "/OCuLink/SCL")
			(pinfunction "SCL")
			(pintype "bidirectional")
		)
		(pad "A10" smd roundrect
			(at -0.25 -2.115 270)
			(size 0.91 0.31)
			(layers "F.Cu" "F.Mask" "F.Paste")
			(roundrect_rratio 0.5)
			(net 226 "/OCuLink/SDA")
			(pinfunction "SDA")
			(pintype "bidirectional")
		)
		(pad "A11" smd roundrect
			(at 0.25 -2.115 270)
			(size 0.91 0.31)
			(layers "F.Cu" "F.Mask" "F.Paste")
			(roundrect_rratio 0.5)
			(net 28 "GND")
			(pinfunction "GND")
			(pintype "passive")
		)
		(pad "A12" smd roundrect
			(at 0.75 -2.115 270)
			(size 0.91 0.31)
			(layers "F.Cu" "F.Mask" "F.Paste")
			(roundrect_rratio 0.5)
			(net 319 "/OCuLink/~{PE_ RST}_R")
			(pinfunction "~{PERST}")
			(pintype "bidirectional")
		)
		(pad "A13" smd roundrect
			(at 1.25 -2.115 270)
			(size 0.91 0.31)
			(layers "F.Cu" "F.Mask" "F.Paste")
			(roundrect_rratio 0.5)
			(net 321 "/OCuLink/~{CPRSNT}_R")
			(pinfunction "~{CPRSNT}")
			(pintype "bidirectional")
		)
		(pad "A14" smd roundrect
			(at 1.75 -2.115 270)
			(size 0.91 0.31)
			(layers "F.Cu" "F.Mask" "F.Paste")
			(roundrect_rratio 0.5)
			(net 28 "GND")
			(pinfunction "GND")
			(pintype "passive")
		)
		(pad "A15" smd roundrect
			(at 2.25 -2.115 270)
			(size 0.91 0.31)
			(layers "F.Cu" "F.Mask" "F.Paste")
			(roundrect_rratio 0.5)
			(net 80 "/OCuLink/PCIe_{x4}.RX2+")
			(pinfunction "PER2+")
			(pintype "output")
		)
		(pad "A16" smd roundrect
			(at 2.75 -2.115 270)
			(size 0.91 0.31)
			(layers "F.Cu" "F.Mask" "F.Paste")
			(roundrect_rratio 0.5)
			(net 104 "/OCuLink/PCIe_{x4}.RX2-")
			(pinfunction "PER2-")
			(pintype "output")
		)
		(pad "A17" smd roundrect
			(at 3.25 -2.115 270)
			(size 0.91 0.31)
			(layers "F.Cu" "F.Mask" "F.Paste")
			(roundrect_rratio 0.5)
			(net 28 "GND")
			(pinfunction "GND")
			(pintype "passive")
		)
		(pad "A18" smd roundrect
			(at 3.75 -2.115 270)
			(size 0.91 0.31)
			(layers "F.Cu" "F.Mask" "F.Paste")
			(roundrect_rratio 0.5)
			(net 98 "/OCuLink/PCIe_{x4}.RX3+")
			(pinfunction "PER3+")
			(pintype "output")
		)
		(pad "A19" smd roundrect
			(at 4.25 -2.115 270)
			(size 0.91 0.31)
			(layers "F.Cu" "F.Mask" "F.Paste")
			(roundrect_rratio 0.5)
			(net 109 "/OCuLink/PCIe_{x4}.RX3-")
			(pinfunction "PER3-")
			(pintype "output")
		)
		(pad "A20" smd roundrect
			(at 4.75 -2.115 270)
			(size 0.91 0.31)
			(layers "F.Cu" "F.Mask" "F.Paste")
			(roundrect_rratio 0.5)
			(net 28 "GND")
			(pinfunction "GND")
			(pintype "passive")
		)
		(pad "A21" smd roundrect
			(at 5.25 -2.115 270)
			(size 0.91 0.31)
			(layers "F.Cu" "F.Mask" "F.Paste")
			(roundrect_rratio 0.5)
			(net 152 "unconnected-(J9-5V-PadA21)")
			(pinfunction "5V")
			(pintype "passive+no_connect")
		)
		(pad "B1" smd roundrect
			(at -5.25 -4.305 270)
			(size 0.91 0.31)
			(layers "F.Cu" "F.Mask" "F.Paste")
			(roundrect_rratio 0.5)
			(net 154 "unconnected-(J9-5V-PadA21)_1")
			(pinfunction "5V")
			(pintype "passive+no_connect")
		)
		(pad "B2" smd roundrect
			(at -4.75 -4.305 270)
			(size 0.91 0.31)
			(layers "F.Cu" "F.Mask" "F.Paste")
			(roundrect_rratio 0.5)
			(net 28 "GND")
			(pinfunction "GND")
			(pintype "passive")
		)
		(pad "B3" smd roundrect
			(at -4.25 -4.305 270)
			(size 0.91 0.31)
			(layers "F.Cu" "F.Mask" "F.Paste")
			(roundrect_rratio 0.5)
			(net 13 "/OCuLink/PCIe_{x4}.TX0+")
			(pinfunction "PET0+")
			(pintype "input")
		)
		(pad "B4" smd roundrect
			(at -3.75 -4.305 270)
			(size 0.91 0.31)
			(layers "F.Cu" "F.Mask" "F.Paste")
			(roundrect_rratio 0.5)
			(net 17 "/OCuLink/PCIe_{x4}.TX0-")
			(pinfunction "PET0-")
			(pintype "input")
		)
		(pad "B5" smd roundrect
			(at -3.25 -4.305 270)
			(size 0.91 0.31)
			(layers "F.Cu" "F.Mask" "F.Paste")
			(roundrect_rratio 0.5)
			(net 28 "GND")
			(pinfunction "GND")
			(pintype "passive")
		)
		(pad "B6" smd roundrect
			(at -2.75 -4.305 270)
			(size 0.91 0.31)
			(layers "F.Cu" "F.Mask" "F.Paste")
			(roundrect_rratio 0.5)
			(net 19 "/OCuLink/PCIe_{x4}.TX1+")
			(pinfunction "PET1+")
			(pintype "input")
		)
		(pad "B7" smd roundrect
			(at -2.25 -4.305 270)
			(size 0.91 0.31)
			(layers "F.Cu" "F.Mask" "F.Paste")
			(roundrect_rratio 0.5)
			(net 20 "/OCuLink/PCIe_{x4}.TX1-")
			(pinfunction "PET1-")
			(pintype "input")
		)
		(pad "B8" smd roundrect
			(at -1.75 -4.305 270)
			(size 0.91 0.31)
			(layers "F.Cu" "F.Mask" "F.Paste")
			(roundrect_rratio 0.5)
			(net 28 "GND")
			(pinfunction "GND")
			(pintype "passive")
		)
		(pad "B9" smd roundrect
			(at -1.25 -4.305 270)
			(size 0.91 0.31)
			(layers "F.Cu" "F.Mask" "F.Paste")
			(roundrect_rratio 0.5)
			(net 151 "unconnected-(J9-NC-PadB9)")
			(pinfunction "NC")
			(pintype "no_connect")
		)
		(pad "B10" smd roundrect
			(at -0.75 -4.305 270)
			(size 0.91 0.31)
			(layers "F.Cu" "F.Mask" "F.Paste")
			(roundrect_rratio 0.5)
			(net 320 "/OCuLink/~{CWAKE}_R")
			(pinfunction "~{CWAKE}")
			(pintype "bidirectional")
		)
		(pad "B11" smd roundrect
			(at -0.25 -4.305 270)
			(size 0.91 0.31)
			(layers "F.Cu" "F.Mask" "F.Paste")
			(roundrect_rratio 0.5)
			(net 28 "GND")
			(pinfunction "GND")
			(pintype "passive")
		)
		(pad "B12" smd roundrect
			(at 0.25 -4.305 270)
			(size 0.91 0.31)
			(layers "F.Cu" "F.Mask" "F.Paste")
			(roundrect_rratio 0.5)
			(net 42 "/OCuLink/REFCLK.+")
			(pinfunction "VSP1")
			(pintype "bidirectional")
		)
		(pad "B13" smd roundrect
			(at 0.75 -4.305 270)
			(size 0.91 0.31)
			(layers "F.Cu" "F.Mask" "F.Paste")
			(roundrect_rratio 0.5)
			(net 45 "/OCuLink/REFCLK.-")
			(pinfunction "VSP2")
			(pintype "bidirectional")
		)
		(pad "B14" smd roundrect
			(at 1.25 -4.305 270)
			(size 0.91 0.31)
			(layers "F.Cu" "F.Mask" "F.Paste")
			(roundrect_rratio 0.5)
			(net 28 "GND")
			(pinfunction "GND")
			(pintype "passive")
		)
		(pad "B15" smd roundrect
			(at 1.75 -4.305 270)
			(size 0.91 0.31)
			(layers "F.Cu" "F.Mask" "F.Paste")
			(roundrect_rratio 0.5)
			(net 21 "/OCuLink/PCIe_{x4}.TX2+")
			(pinfunction "PET2+")
			(pintype "input")
		)
		(pad "B16" smd roundrect
			(at 2.25 -4.305 270)
			(size 0.91 0.31)
			(layers "F.Cu" "F.Mask" "F.Paste")
			(roundrect_rratio 0.5)
			(net 22 "/OCuLink/PCIe_{x4}.TX2-")
			(pinfunction "PET2-")
			(pintype "input")
		)
		(pad "B17" smd roundrect
			(at 2.75 -4.305 270)
			(size 0.91 0.31)
			(layers "F.Cu" "F.Mask" "F.Paste")
			(roundrect_rratio 0.5)
			(net 28 "GND")
			(pinfunction "GND")
			(pintype "passive")
		)
		(pad "B18" smd roundrect
			(at 3.25 -4.305 270)
			(size 0.91 0.31)
			(layers "F.Cu" "F.Mask" "F.Paste")
			(roundrect_rratio 0.5)
			(net 25 "/OCuLink/PCIe_{x4}.TX3+")
			(pinfunction "PET3+")
			(pintype "input")
		)
		(pad "B19" smd roundrect
			(at 3.75 -4.305 270)
			(size 0.91 0.31)
			(layers "F.Cu" "F.Mask" "F.Paste")
			(roundrect_rratio 0.5)
			(net 26 "/OCuLink/PCIe_{x4}.TX3-")
			(pinfunction "PET3-")
			(pintype "input")
		)
		(pad "B20" smd roundrect
			(at 4.25 -4.305 270)
			(size 0.91 0.31)
			(layers "F.Cu" "F.Mask" "F.Paste")
			(roundrect_rratio 0.5)
			(net 28 "GND")
			(pinfunction "GND")
			(pintype "passive")
		)
		(pad "B21" smd roundrect
			(at 4.75 -4.305 270)
			(size 0.91 0.31)
			(layers "F.Cu" "F.Mask" "F.Paste")
			(roundrect_rratio 0.5)
			(net 90 "+3V3_AUX")
			(pinfunction "V_{ACT}_TX_3V3")
			(pintype "power_in")
		)
		(pad "SH" smd roundrect
			(at -6.91 -3.915 270)
			(size 1.38 1.81)
			(layers "F.Cu" "F.Mask" "F.Paste")
			(roundrect_rratio 0.1)
			(net 28 "GND")
			(pinfunction "SH")
			(pintype "passive")
		)
		(pad "SH" smd roundrect
			(at -6.91 0.805 270)
			(size 1.81 1.8)
			(layers "F.Cu" "F.Mask" "F.Paste")
			(roundrect_rratio 0.1)
			(net 28 "GND")
			(pinfunction "SH")
			(pintype "passive")
		)
		(pad "SH" smd roundrect
			(at 6.91 -3.915 270)
			(size 1.38 1.81)
			(layers "F.Cu" "F.Mask" "F.Paste")
			(roundrect_rratio 0.1)
			(net 28 "GND")
			(pinfunction "SH")
			(pintype "passive")
		)
		(pad "SH" smd roundrect
			(at 6.91 0.805 270)
			(size 1.81 1.8)
			(layers "F.Cu" "F.Mask" "F.Paste")
			(roundrect_rratio 0.1)
			(net 28 "GND")
			(pinfunction "SH")
			(pintype "passive")
		)
	)
	(footprint "antmicro-footprints:MP_Pad6mm_Drill3.2mm"
		(layer "F.Cu")
		(at 56.75 134.68)
		(property "Reference" "MP1"
			(at -0.9 -3.48 0)
			(layer "F.SilkS")
			(hide yes)
			(effects
				(font
					(size 0.7 0.7)
					(thickness 0.15)
				)
				(justify left bottom)
			)
		)
		(property "Value" "MP_Pad6mm_Drill3.2mm"
			(at 0 3.9 0)
			(layer "F.Fab")
			(hide yes)
			(effects
				(font
					(size 0.7 0.7)
					(thickness 0.15)
				)
				(justify left bottom)
			)
		)
		(property "Description" "Mechanical part"
			(at 0 0 0)
			(layer "F.Fab")
			(hide yes)
			(effects
				(font
					(size 1.27 1.27)
					(thickness 0.15)
				)
			)
		)
		(property "Author" "Antmicro"
			(at 0 0 0)
			(unlocked yes)
			(layer "F.Fab")
			(hide yes)
			(effects
				(font
					(size 1 1)
					(thickness 0.15)
				)
			)
		)
		(property "License" "Apache-2.0"
			(at 0 0 0)
			(unlocked yes)
			(layer "F.Fab")
			(hide yes)
			(effects
				(font
					(size 1 1)
					(thickness 0.15)
				)
			)
		)
		(sheetname "/")
		(sheetfile "oculink-to-10gbe-adapter.kicad_sch")
		(attr exclude_from_pos_files exclude_from_bom)
		(fp_circle
			(center 0 0)
			(end 3.25 0)
			(stroke
				(width 0.05)
				(type default)
			)
			(fill no)
			(layer "F.CrtYd")
		)
		(pad "1" thru_hole circle
			(at 0 0)
			(size 6 6)
			(drill 3.2)
			(layers "*.Cu" "*.Mask")
			(remove_unused_layers no)
			(net 28 "GND")
			(pintype "passive")
		)
	)
	(footprint "antmicro-footprints:C_0603_1608Metric_EIA"
		(layer "F.Cu")
		(at 63.199999 108.55 180)
		(descr "Capacitor SMD 0603, IPC-7351 Density Level A")
		(tags "Capacitor 0603")
		(property "Reference" "C207"
			(at -2.620001 2.68 0)
			(layer "F.SilkS")
			(effects
				(font
					(size 0.7 0.7)
					(thickness 0.15)
				)
				(justify right top)
			)
		)
		(property "Value" "C_22u_16V_0603"
			(at -1.42757 1.770288 0)
			(layer "F.Fab")
			(hide yes)
			(effects
				(font
					(size 0.7 0.7)
					(thickness 0.15)
				)
				(justify right top)
			)
		)
		(property "Datasheet" "https://product.samsungsem.com/mlcc/CL10A226MO7JZN.do"
			(at 0 0 0)
			(layer "F.Fab")
			(hide yes)
			(effects
				(font
					(size 1.27 1.27)
					(thickness 0.15)
				)
			)
		)
		(property "Description" "SMD Multilayer Ceramic Capacitor"
			(at 0 0 0)
			(layer "F.Fab")
			(hide yes)
			(effects
				(font
					(size 1.27 1.27)
					(thickness 0.15)
				)
			)
		)
		(property "MPN" "CL10A226MO7JZNC"
			(at 0 0 180)
			(unlocked yes)
			(layer "F.Fab")
			(hide yes)
			(effects
				(font
					(size 1 1)
					(thickness 0.15)
				)
			)
		)
		(property "Manufacturer" "Samsung Electro-Mechanics"
			(at 0 0 180)
			(unlocked yes)
			(layer "F.Fab")
			(hide yes)
			(effects
				(font
					(size 1 1)
					(thickness 0.15)
				)
			)
		)
		(property "License" "Apache-2.0"
			(at 0 0 180)
			(unlocked yes)
			(layer "F.Fab")
			(hide yes)
			(effects
				(font
					(size 1 1)
					(thickness 0.15)
				)
			)
		)
		(property "Author" "Antmicro"
			(at 0 0 180)
			(unlocked yes)
			(layer "F.Fab")
			(hide yes)
			(effects
				(font
					(size 1 1)
					(thickness 0.15)
				)
			)
		)
		(property "Val" "22u"
			(at 0 0 180)
			(unlocked yes)
			(layer "F.Fab")
			(hide yes)
			(effects
				(font
					(size 1 1)
					(thickness 0.15)
				)
			)
		)
		(property "Voltage" "16V"
			(at 0 0 180)
			(unlocked yes)
			(layer "F.Fab")
			(hide yes)
			(effects
				(font
					(size 1 1)
					(thickness 0.15)
				)
			)
		)
		(property "Dielectric" ""
			(at 0 0 180)
			(unlocked yes)
			(layer "F.Fab")
			(hide yes)
			(effects
				(font
					(size 1 1)
					(thickness 0.15)
				)
			)
		)
		(property "Public" "False"
			(at 0 0 180)
			(unlocked yes)
			(layer "F.Fab")
			(hide yes)
			(effects
				(font
					(size 1 1)
					(thickness 0.15)
				)
			)
		)
		(sheetname "/Power/")
		(sheetfile "power.kicad_sch")
		(attr smd)
		(fp_line
			(start -0.15 0.55)
			(end 0.15 0.55)
			(stroke
				(width 0.15)
				(type solid)
			)
			(layer "F.SilkS")
		)
		(fp_line
			(start -0.15 -0.55)
			(end 0.15 -0.55)
			(stroke
				(width 0.15)
				(type solid)
			)
			(layer "F.SilkS")
		)
		(fp_rect
			(start -1.25 -0.65)
			(end 1.25 0.65)
			(stroke
				(width 0.05)
				(type solid)
			)
			(fill no)
			(layer "F.CrtYd")
		)
		(fp_rect
			(start -0.8 -0.45)
			(end 0.8 0.45)
			(stroke
				(width 0.15)
				(type solid)
			)
			(fill no)
			(layer "F.Fab")
		)
		(pad "1" smd roundrect
			(at -0.7 0 180)
			(size 0.8 1.1)
			(layers "F.Cu" "F.Mask" "F.Paste")
			(roundrect_rratio 0.2)
			(net 28 "GND")
			(pintype "passive")
		)
		(pad "2" smd roundrect
			(at 0.7 0 180)
			(size 0.8 1.1)
			(layers "F.Cu" "F.Mask" "F.Paste")
			(roundrect_rratio 0.2)
			(net 312 "/Power/+1V0_OUT")
			(pintype "passive")
		)
	)
)
